# TIMECARD (Time Appliance Project (Time Card)) — schematic netlist excerpt (pin names and nets, part order shuffled) for the footprints in the layout excerpt that follows; sources: Cadence DE-HDL packaged netlist, KiCad conversion of R4006-B0001-02_R01.brd

CR4  DIODE_4_V1  pkg SOT143  page 23
  GND  = SG
  IO1  = SMA2_SIG_IO_CONN
  IO2  = SMA1_SIG_IO_CONN
  VDD  = NC

(kicad_pcb
	(version 20260206)
	(generator "pcbnew")
	(generator_version "10.0")
	(general
		(thickness 1.6)
		(legacy_teardrops no)
	)
	(paper "A4")
	(title_block
		(title "timecard-production-celestica-r4006 — R4006-B0001-02_R01.brd")
		(comment 1 "Time Appliance Project (Time Card) / footprints 601-601 of 1113")
	)
	(layers
		(0 "F.Cu" signal "TOP")
		(4 "In1.Cu" signal "L02_GND1")
		(6 "In2.Cu" signal "L03_SIG1")
		(8 "In3.Cu" signal "L04_GND2")
		(10 "In4.Cu" signal "L05_VCC1")
		(12 "In5.Cu" signal "L06_VCC2")
		(14 "In6.Cu" signal "L07_GND3")
		(16 "In7.Cu" signal "L08_SIG2")
		(18 "In8.Cu" signal "L09_GND4")
		(2 "B.Cu" signal "BOTTOM")
		(9 "F.Adhes" user "F.Adhesive")
		(11 "B.Adhes" user "B.Adhesive")
		(13 "F.Paste" user "Package Geometry/Pastemask Top")
		(15 "B.Paste" user "Package Geometry/Pastemask Bottom")
		(5 "F.SilkS" user "Ref Des/Silkscreen Top")
		(7 "B.SilkS" user "Ref Des/Silkscreen Bottom")
		(1 "F.Mask" user "Board Geometry/Soldermask Top")
		(3 "B.Mask" user "Board Geometry/Soldermask Bottom")
		(17 "Dwgs.User" user "User.Drawings")
		(19 "Cmts.User" user "User.Comments")
		(21 "Eco1.User" user "User.Eco1")
		(23 "Eco2.User" user "User.Eco2")
		(25 "Edge.Cuts" user "Board Geometry/Outline")
		(27 "Margin" user)
		(31 "F.CrtYd" user "Package Geometry/Place Bound Top")
		(29 "B.CrtYd" user "Package Geometry/Place Bound Bottom")
		(35 "F.Fab" user "Ref Des/Assembly Top")
		(33 "B.Fab" user "Ref Des/Assembly Bottom")
	)
	(footprint ""
		(layer "F.Cu")
		(at 5.969 -54.356 90)
		(property "Reference" "CR4"
			(at 0.381 2.57937 90)
			(unlocked yes)
			(layer "F.SilkS")
			(effects
				(font
					(size 0.7874 0.5842)
					(thickness 0.1524)
				)
			)
		)
		(property "Value" ""
			(at 0 0 90)
			(layer "F.Fab")
			(effects
				(font
					(size 1.27 1.27)
				)
			)
		)
		(property "Device Type" "DIODE_4_V1-G122-10123-01"
			(at 0.254 2.702306 90)
			(unlocked yes)
			(layer "F.Fab")
			(hide yes)
			(effects
				(font
					(size 0.7874 0.5842)
					(thickness 0.1524)
				)
			)
		)
		(property "User Part Number" "PARTNUM*"
			(at 0.254 3.718306 90)
			(unlocked yes)
			(layer "Cmts.User")
			(hide yes)
			(effects
				(font
					(size 0.7874 0.5842)
					(thickness 0.1524)
				)
			)
		)
		(duplicate_pad_numbers_are_jumpers no)
		(fp_line
			(start 2.0828 -1.7018)
			(end 2.0828 1.7018)
			(stroke
				(width 0.1)
				(type default)
			)
			(layer "F.SilkS")
		)
		(fp_line
			(start -2.0828 -1.7018)
			(end 2.0828 -1.7018)
			(stroke
				(width 0.1)
				(type default)
			)
			(layer "F.SilkS")
		)
		(fp_line
			(start 2.0828 1.7018)
			(end -2.0828 1.7018)
			(stroke
				(width 0.1)
				(type default)
			)
			(layer "F.SilkS")
		)
		(fp_line
			(start -2.0828 1.7018)
			(end -2.0828 -1.7018)
			(stroke
				(width 0.1)
				(type default)
			)
			(layer "F.SilkS")
		)
		(fp_poly
			(pts
				(arc
					(start -2.6162 -0.508)
					(mid -2.6162 -1.27)
					(end -2.6162 -0.508)
				)
			)
			(stroke
				(width 0)
				(type default)
			)
			(fill yes)
			(layer "F.SilkS")
		)
		(fp_rect
			(start -2.3368 -1.9304)
			(end 2.3368 1.9304)
			(stroke
				(width 0)
				(type default)
			)
			(fill no)
			(layer "F.CrtYd")
		)
		(fp_line
			(start 0.6477 -1.42875)
			(end 0.6477 1.42875)
			(stroke
				(width 0.1)
				(type default)
			)
			(layer "F.Fab")
		)
		(fp_line
			(start -0.6477 -1.42875)
			(end 0.6477 -1.42875)
			(stroke
				(width 0.1)
				(type default)
			)
			(layer "F.Fab")
		)
		(fp_line
			(start 1.143 -1.1811)
			(end 1.143 -0.7239)
			(stroke
				(width 0.1)
				(type default)
			)
			(layer "F.Fab")
		)
		(fp_line
			(start 0.6477 -1.1811)
			(end 1.143 -1.1811)
			(stroke
				(width 0.1)
				(type default)
			)
			(layer "F.Fab")
		)
		(fp_line
			(start -0.6477 -1.1811)
			(end -0.6477 -0.3175)
			(stroke
				(width 0.1)
				(type default)
			)
			(layer "F.Fab")
		)
		(fp_line
			(start -1.143 -1.1811)
			(end -0.6477 -1.1811)
			(stroke
				(width 0.1)
				(type default)
			)
			(layer "F.Fab")
		)
		(fp_line
			(start 1.143 -0.7239)
			(end 0.6477 -0.7239)
			(stroke
				(width 0.1)
				(type default)
			)
			(layer "F.Fab")
		)
		(fp_line
			(start 0.6477 -0.7239)
			(end 0.6477 -1.1811)
			(stroke
				(width 0.1)
				(type default)
			)
			(layer "F.Fab")
		)
		(fp_line
			(start -0.6477 -0.3175)
			(end -1.143 -0.3175)
			(stroke
				(width 0.1)
				(type default)
			)
			(layer "F.Fab")
		)
		(fp_line
			(start -1.143 -0.3175)
			(end -1.143 -1.1811)
			(stroke
				(width 0.1)
				(type default)
			)
			(layer "F.Fab")
		)
		(fp_line
			(start 1.143 0.7239)
			(end 1.143 1.1811)
			(stroke
				(width 0.1)
				(type default)
			)
			(layer "F.Fab")
		)
		(fp_line
			(start 0.6477 0.7239)
			(end 1.143 0.7239)
			(stroke
				(width 0.1)
				(type default)
			)
			(layer "F.Fab")
		)
		(fp_line
			(start -0.6477 0.7239)
			(end -0.6477 1.1811)
			(stroke
				(width 0.1)
				(type default)
			)
			(layer "F.Fab")
		)
		(fp_line
			(start -1.143 0.7239)
			(end -0.6477 0.7239)
			(stroke
				(width 0.1)
				(type default)
			)
			(layer "F.Fab")
		)
		(fp_line
			(start 1.143 1.1811)
			(end 0.6477 1.1811)
			(stroke
				(width 0.1)
				(type default)
			)
			(layer "F.Fab")
		)
		(fp_line
			(start 0.6477 1.1811)
			(end 0.6477 0.7239)
			(stroke
				(width 0.1)
				(type default)
			)
			(layer "F.Fab")
		)
		(fp_line
			(start -0.6477 1.1811)
			(end -1.143 1.1811)
			(stroke
				(width 0.1)
				(type default)
			)
			(layer "F.Fab")
		)
		(fp_line
			(start -1.143 1.1811)
			(end -1.143 0.7239)
			(stroke
				(width 0.1)
				(type default)
			)
			(layer "F.Fab")
		)
		(fp_line
			(start 0.6477 1.42875)
			(end -0.6477 1.42875)
			(stroke
				(width 0.1)
				(type default)
			)
			(layer "F.Fab")
		)
		(fp_line
			(start -0.6477 1.42875)
			(end -0.6477 -1.42875)
			(stroke
				(width 0.1)
				(type default)
			)
			(layer "F.Fab")
		)
		(fp_poly
			(pts
				(arc
					(start -0.381 -0.5588)
					(mid -0.381 -0.9398)
					(end -0.381 -0.5588)
				)
			)
			(stroke
				(width 0)
				(type default)
			)
			(fill yes)
			(layer "F.Fab")
		)
		(fp_text user "4"
			(at 1.36525 -2.3622 0)
			(unlocked yes)
			(layer "F.SilkS")
			(effects
				(font
					(size 0.635 0.4064)
					(thickness 0.1524)
				)
				(justify left)
			)
		)
		(fp_text user "2"
			(at -2.57175 2.0828 0)
			(unlocked yes)
			(layer "F.SilkS")
			(effects
				(font
					(size 0.635 0.4064)
					(thickness 0.1524)
				)
				(justify left)
			)
		)
		(fp_text user "3"
			(at 1.92405 2.1209 0)
			(unlocked yes)
			(layer "F.SilkS")
			(effects
				(font
					(size 0.635 0.4064)
					(thickness 0.1524)
				)
				(justify left)
			)
		)
		(fp_text user "4"
			(at 1.668526 -1.822704 0)
			(unlocked yes)
			(layer "F.Fab")
			(effects
				(font
					(size 0.7874 0.5842)
					(thickness 0.1524)
				)
				(justify left)
			)
		)
		(fp_text user "2"
			(at -1.887474 0.844296 0)
			(unlocked yes)
			(layer "F.Fab")
			(effects
				(font
					(size 0.7874 0.5842)
					(thickness 0.1524)
				)
				(justify left)
			)
		)
		(fp_text user "3"
			(at 1.287526 1.479296 0)
			(unlocked yes)
			(layer "F.Fab")
			(effects
				(font
					(size 0.7874 0.5842)
					(thickness 0.1524)
				)
				(justify left)
			)
		)
		(pad "1" smd rect
			(at -1.1049 -0.7493 90)
			(size 1.4478 1.0922)
			(layers "F.Cu" "F.Mask" "F.Paste")
			(net "SG")
		)
		(pad "2" smd rect
			(at -1.1049 0.9525 90)
			(size 1.4478 0.9906)
			(layers "F.Cu" "F.Mask" "F.Paste")
			(net "SMA2_SIG_IO_CONN")
		)
		(pad "3" smd rect
			(at 1.1049 0.9525 90)
			(size 1.4478 0.9906)
			(layers "F.Cu" "F.Mask" "F.Paste")
			(net "SMA1_SIG_IO_CONN")
		)
		(pad "4" smd rect
			(at 1.1049 -0.9525 90)
			(size 1.4478 0.9906)
			(layers "F.Cu" "F.Mask" "F.Paste")
			(net "Net_567")
		)
		(zone
			(layer "F.Cu")
			(hatch none 0.5)
			(connect_pads
				(clearance 0)
			)
			(min_thickness 0.25)
			(keepout
				(tracks allowed)
				(vias not_allowed)
				(pads allowed)
				(copperpour not_allowed)
				(footprints allowed)
			)
			(placement
				(enabled no)
				(sheetname "")
			)
			(fill
				(thermal_gap 0.5)
				(thermal_bridge_width 0.5)
				(island_removal_mode 0)
			)
			(polygon
				(pts
					(xy 4.6736 -53.7083) (xy 4.5339 -53.7083) (xy 4.5339 -54.737) (xy 5.5118 -54.737) (xy 5.5118 -55.0037)
					(xy 6.4262 -55.0037) (xy 6.4262 -54.737) (xy 7.4041 -54.737) (xy 7.4041 -53.975) (xy 6.4262 -53.975)
					(xy 6.4262 -53.7083) (xy 5.7658 -53.7083) (xy 5.7658 -53.975) (xy 4.6736 -53.975)
				)
			)
		)
	)
)
